# S9S_MB_2U (Grand Teton) — schematic netlist excerpt (pin names and nets, part order shuffled) for the footprints in the layout excerpt that follows; sources: Cadence DE-HDL packaged netlist, KiCad conversion of 03242023_DA0F0TMBIJ0_F0T_Motherboard_J_brd_V01_OCP.brd

PC1182_P0_4  Q_CAP  22UF 16V 20% X6S  pkg C0805  page 272 : A = SW_P12V_PVCCFA_EHV_FIVRA_CPU0_L ; B = GND
R589  Q_RES  33.2 1% CHIP  pkg 0402LF  page 231 : A = SMB_PCIE0_3V3AUX_SDA ; B = SMB_PCIE0_3V3AUX_SDA_R
C561  Q_CAP  0.1UF 25V 10% X7R  pkg 0402  page 235 : A = P3V3_AUX ; B = GND

(kicad_pcb
	(version 20260206)
	(generator "pcbnew")
	(generator_version "10.0")
	(general
		(thickness 1.6)
		(legacy_teardrops no)
	)
	(paper "A4")
	(title_block
		(title "03242023_DA0F0TMBIJ0_F0T_Motherboard_J_brd_V01_OCP.brd")
		(comment 1 "Grand Teton / footprints 6048-6050 of 6105")
	)
	(layers
		(0 "F.Cu" signal "TOP")
		(4 "In1.Cu" signal "GND")
		(6 "In2.Cu" signal "IN1")
		(8 "In3.Cu" signal "GND1")
		(10 "In4.Cu" signal "IN2")
		(12 "In5.Cu" signal "GND2")
		(14 "In6.Cu" signal "IN3")
		(16 "In7.Cu" signal "GND3")
		(18 "In8.Cu" signal "VCC")
		(20 "In9.Cu" signal "VCC1")
		(22 "In10.Cu" signal "GND4")
		(24 "In11.Cu" signal "IN4")
		(26 "In12.Cu" signal "GND5")
		(28 "In13.Cu" signal "IN5")
		(30 "In14.Cu" signal "GND6")
		(32 "In15.Cu" signal "IN6")
		(34 "In16.Cu" signal "GND7")
		(2 "B.Cu" signal "BOTTOM")
		(9 "F.Adhes" user "F.Adhesive")
		(11 "B.Adhes" user "B.Adhesive")
		(13 "F.Paste" user "Package Geometry/Pastemask Top")
		(15 "B.Paste" user "Package Geometry/Pastemask Bottom")
		(5 "F.SilkS" user "Ref Des/Silkscreen Top")
		(7 "B.SilkS" user "Ref Des/Silkscreen Bottom")
		(1 "F.Mask" user "Board Geometry/Soldermask Top")
		(3 "B.Mask" user "Board Geometry/Soldermask Bottom")
		(17 "Dwgs.User" user "User.Drawings")
		(19 "Cmts.User" user "User.Comments")
		(21 "Eco1.User" user "User.Eco1")
		(23 "Eco2.User" user "User.Eco2")
		(25 "Edge.Cuts" user "Board Geometry/Outline")
		(27 "Margin" user)
		(31 "F.CrtYd" user "Package Geometry/Place Bound Top")
		(29 "B.CrtYd" user "Package Geometry/Place Bound Bottom")
		(35 "F.Fab" user "Ref Des/Assembly Top")
		(33 "B.Fab" user "Ref Des/Assembly Bottom")
	)
	(footprint ""
		(layer "B.Cu")
		(at 367.778538 -189.56147)
		(property "Reference" "C561"
			(at 0 0 0)
			(layer "B.SilkS")
			(hide yes)
			(effects
				(font
					(size 1.27 1.27)
				)
				(justify mirror)
			)
		)
		(property "Value" ""
			(at 0 0 0)
			(layer "B.Fab")
			(effects
				(font
					(size 1.27 1.27)
				)
				(justify mirror)
			)
		)
		(duplicate_pad_numbers_are_jumpers no)
		(fp_line
			(start -0.7874 -0.4064)
			(end -0.7874 0.4064)
			(stroke
				(width 0.1524)
				(type default)
			)
			(layer "B.SilkS")
		)
		(fp_line
			(start -0.7874 0.4064)
			(end 0.7874 0.4064)
			(stroke
				(width 0.1524)
				(type default)
			)
			(layer "B.SilkS")
		)
		(fp_line
			(start 0.7874 -0.4064)
			(end -0.7874 -0.4064)
			(stroke
				(width 0.1524)
				(type default)
			)
			(layer "B.SilkS")
		)
		(fp_line
			(start 0.7874 0.4064)
			(end 0.7874 -0.4064)
			(stroke
				(width 0.1524)
				(type default)
			)
			(layer "B.SilkS")
		)
		(fp_line
			(start -0.67945 -0.3048)
			(end -0.67945 0.3048)
			(stroke
				(width 0.1)
				(type default)
			)
			(layer "B.Fab")
		)
		(fp_line
			(start -0.67945 0.3048)
			(end -0.120396 0.3048)
			(stroke
				(width 0.1)
				(type default)
			)
			(layer "B.Fab")
		)
		(fp_line
			(start -0.12065 -0.3048)
			(end -0.67945 -0.3048)
			(stroke
				(width 0.1)
				(type default)
			)
			(layer "B.Fab")
		)
		(fp_line
			(start -0.12065 -0.2794)
			(end -0.12065 -0.3048)
			(stroke
				(width 0.1)
				(type default)
			)
			(layer "B.Fab")
		)
		(fp_line
			(start -0.120396 0.2794)
			(end 0.12065 0.2794)
			(stroke
				(width 0.1)
				(type default)
			)
			(layer "B.Fab")
		)
		(fp_line
			(start -0.120396 0.3048)
			(end -0.120396 0.2794)
			(stroke
				(width 0.1)
				(type default)
			)
			(layer "B.Fab")
		)
		(fp_line
			(start 0.12065 -0.305054)
			(end 0.12065 -0.2794)
			(stroke
				(width 0.1)
				(type default)
			)
			(layer "B.Fab")
		)
		(fp_line
			(start 0.12065 -0.2794)
			(end -0.12065 -0.2794)
			(stroke
				(width 0.1)
				(type default)
			)
			(layer "B.Fab")
		)
		(fp_line
			(start 0.12065 0.2794)
			(end 0.12065 0.3048)
			(stroke
				(width 0.1)
				(type default)
			)
			(layer "B.Fab")
		)
		(fp_line
			(start 0.12065 0.3048)
			(end 0.67945 0.3048)
			(stroke
				(width 0.1)
				(type default)
			)
			(layer "B.Fab")
		)
		(fp_line
			(start 0.67945 -0.305054)
			(end 0.12065 -0.305054)
			(stroke
				(width 0.1)
				(type default)
			)
			(layer "B.Fab")
		)
		(fp_line
			(start 0.67945 0.3048)
			(end 0.67945 -0.305054)
			(stroke
				(width 0.1)
				(type default)
			)
			(layer "B.Fab")
		)
		(pad "1" smd circle
			(at 0.40005 0 180)
			(size 0 0)
			(layers "B.Cu" "B.Mask" "B.Paste")
			(net "P3V3_AUX")
		)
		(pad "2" smd circle
			(at -0.40005 0 180)
			(size 0 0)
			(layers "B.Cu" "B.Mask" "B.Paste")
			(net "GND")
		)
	)
	(footprint ""
		(layer "B.Cu")
		(at 163.851082 -8.916924 90)
		(property "Reference" "R589"
			(at 0 0 90)
			(layer "B.SilkS")
			(hide yes)
			(effects
				(font
					(size 1.27 1.27)
				)
				(justify mirror)
			)
		)
		(property "Value" ""
			(at 0 0 90)
			(layer "B.Fab")
			(effects
				(font
					(size 1.27 1.27)
				)
				(justify mirror)
			)
		)
		(duplicate_pad_numbers_are_jumpers no)
		(fp_line
			(start 0.7874 -0.4064)
			(end -0.7874 -0.4064)
			(stroke
				(width 0.1524)
				(type default)
			)
			(layer "B.SilkS")
		)
		(fp_line
			(start -0.7874 -0.4064)
			(end -0.7874 0.4064)
			(stroke
				(width 0.1524)
				(type default)
			)
			(layer "B.SilkS")
		)
		(fp_line
			(start 0.7874 0.4064)
			(end 0.7874 -0.4064)
			(stroke
				(width 0.1524)
				(type default)
			)
			(layer "B.SilkS")
		)
		(fp_line
			(start -0.7874 0.4064)
			(end 0.7874 0.4064)
			(stroke
				(width 0.1524)
				(type default)
			)
			(layer "B.SilkS")
		)
		(fp_line
			(start 0.67945 -0.305054)
			(end 0.12065 -0.305054)
			(stroke
				(width 0.1)
				(type default)
			)
			(layer "B.Fab")
		)
		(fp_line
			(start 0.12065 -0.305054)
			(end 0.12065 -0.2794)
			(stroke
				(width 0.1)
				(type default)
			)
			(layer "B.Fab")
		)
		(fp_line
			(start -0.12065 -0.3048)
			(end -0.67945 -0.3048)
			(stroke
				(width 0.1)
				(type default)
			)
			(layer "B.Fab")
		)
		(fp_line
			(start -0.67945 -0.3048)
			(end -0.67945 0.3048)
			(stroke
				(width 0.1)
				(type default)
			)
			(layer "B.Fab")
		)
		(fp_line
			(start 0.12065 -0.2794)
			(end -0.12065 -0.2794)
			(stroke
				(width 0.1)
				(type default)
			)
			(layer "B.Fab")
		)
		(fp_line
			(start -0.12065 -0.2794)
			(end -0.12065 -0.3048)
			(stroke
				(width 0.1)
				(type default)
			)
			(layer "B.Fab")
		)
		(fp_line
			(start 0.12065 0.2794)
			(end 0.12065 0.3048)
			(stroke
				(width 0.1)
				(type default)
			)
			(layer "B.Fab")
		)
		(fp_line
			(start -0.120396 0.2794)
			(end 0.12065 0.2794)
			(stroke
				(width 0.1)
				(type default)
			)
			(layer "B.Fab")
		)
		(fp_line
			(start 0.67945 0.3048)
			(end 0.67945 -0.305054)
			(stroke
				(width 0.1)
				(type default)
			)
			(layer "B.Fab")
		)
		(fp_line
			(start 0.12065 0.3048)
			(end 0.67945 0.3048)
			(stroke
				(width 0.1)
				(type default)
			)
			(layer "B.Fab")
		)
		(fp_line
			(start -0.120396 0.3048)
			(end -0.120396 0.2794)
			(stroke
				(width 0.1)
				(type default)
			)
			(layer "B.Fab")
		)
		(fp_line
			(start -0.67945 0.3048)
			(end -0.120396 0.3048)
			(stroke
				(width 0.1)
				(type default)
			)
			(layer "B.Fab")
		)
		(pad "1" smd circle
			(at 0.40005 0 270)
			(size 0 0)
			(layers "B.Cu" "B.Mask" "B.Paste")
			(net "SMB_PCIE0_3V3AUX_SDA")
		)
		(pad "2" smd circle
			(at -0.40005 0 270)
			(size 0 0)
			(layers "B.Cu" "B.Mask" "B.Paste")
			(net "SMB_PCIE0_3V3AUX_SDA_R")
		)
	)
	(footprint ""
		(layer "B.Cu")
		(at 292.04285 -362.795058 90)
		(property "Reference" "PC1182_P0_4"
			(at 0 0 90)
			(layer "B.SilkS")
			(hide yes)
			(effects
				(font
					(size 1.27 1.27)
				)
				(justify mirror)
			)
		)
		(property "Value" ""
			(at 0 0 90)
			(layer "B.Fab")
			(effects
				(font
					(size 1.27 1.27)
				)
				(justify mirror)
			)
		)
		(duplicate_pad_numbers_are_jumpers no)
		(fp_line
			(start 1.524 -0.762)
			(end -1.524 -0.762)
			(stroke
				(width 0.1524)
				(type default)
			)
			(layer "B.SilkS")
		)
		(fp_line
			(start -1.524 -0.762)
			(end -1.524 0.762)
			(stroke
				(width 0.1524)
				(type default)
			)
			(layer "B.SilkS")
		)
		(fp_line
			(start 1.524 0.762)
			(end 1.524 -0.762)
			(stroke
				(width 0.1524)
				(type default)
			)
			(layer "B.SilkS")
		)
		(fp_line
			(start -1.524 0.762)
			(end 1.524 0.762)
			(stroke
				(width 0.1524)
				(type default)
			)
			(layer "B.SilkS")
		)
		(fp_line
			(start 1.1049 -0.724916)
			(end 1.1049 0.724916)
			(stroke
				(width 0.1)
				(type default)
			)
			(layer "B.Fab")
		)
		(fp_line
			(start -1.1049 -0.724916)
			(end 1.1049 -0.724916)
			(stroke
				(width 0.1)
				(type default)
			)
			(layer "B.Fab")
		)
		(fp_line
			(start 1.1049 0.724916)
			(end -1.1049 0.724916)
			(stroke
				(width 0.1)
				(type default)
			)
			(layer "B.Fab")
		)
		(fp_line
			(start -1.1049 0.724916)
			(end -1.1049 -0.724916)
			(stroke
				(width 0.1)
				(type default)
			)
			(layer "B.Fab")
		)
		(pad "1" smd rect
			(at 0.889 0 90)
			(size 1.016 1.27)
			(layers "B.Cu" "B.Mask" "B.Paste")
			(net "SW_P12V_PVCCFA_EHV_FIVRA_CPU0_L")
		)
		(pad "2" smd rect
			(at -0.889 0 90)
			(size 1.016 1.27)
			(layers "B.Cu" "B.Mask" "B.Paste")
			(net "GND")
		)
	)
)
